(kicad_pcb
	(version 20260206)
	(generator "pcbnew")
	(generator_version "10.0")
	(general
		(thickness 1.6)
		(legacy_teardrops no)
	)
	(paper "A4")
	(title_block
		(title "Wiwynn_Tioga_Pass_MB.brd")
		(comment 1 "Tioga Pass / footprints 3767-3773 of 4770")
	)
	(layers
		(0 "F.Cu" signal "TOP")
		(4 "In1.Cu" signal "L2GND")
		(6 "In2.Cu" signal "L3")
		(8 "In3.Cu" signal "L4GND")
		(10 "In4.Cu" signal "L5")
		(12 "In5.Cu" signal "L6GND")
		(14 "In6.Cu" signal "L7VCC")
		(16 "In7.Cu" signal "L8VCC")
		(18 "In8.Cu" signal "L9GND")
		(20 "In9.Cu" signal "L10")
		(22 "In10.Cu" signal "L11GND")
		(24 "In11.Cu" signal "L12")
		(26 "In12.Cu" signal "L13GND")
		(2 "B.Cu" signal "BOTTOM")
		(9 "F.Adhes" user "F.Adhesive")
		(11 "B.Adhes" user "B.Adhesive")
		(13 "F.Paste" user "Package Geometry/Pastemask Top")
		(15 "B.Paste" user "Package Geometry/Pastemask Bottom")
		(5 "F.SilkS" user "Ref Des/Silkscreen Top")
		(7 "B.SilkS" user "Ref Des/Silkscreen Bottom")
		(1 "F.Mask" user "Board Geometry/Soldermask Top")
		(3 "B.Mask" user "Board Geometry/Soldermask Bottom")
		(17 "Dwgs.User" user "User.Drawings")
		(19 "Cmts.User" user "User.Comments")
		(21 "Eco1.User" user "User.Eco1")
		(23 "Eco2.User" user "User.Eco2")
		(25 "Edge.Cuts" user "Board Geometry/Outline")
		(27 "Margin" user)
		(31 "F.CrtYd" user "Package Geometry/Place Bound Top")
		(29 "B.CrtYd" user "Package Geometry/Place Bound Bottom")
		(35 "F.Fab" user "Ref Des/Assembly Top")
		(33 "B.Fab" user "Ref Des/Assembly Bottom")
	)
	(footprint ""
		(layer "B.Cu")
		(at 373.017288 -36.096448 90)
		(property "Reference" "C7E3"
			(at 0 0 90)
			(layer "B.SilkS")
			(hide yes)
			(effects
				(font
					(size 1.27 1.27)
				)
				(justify mirror)
			)
		)
		(property "Value" ""
			(at 0 0 90)
			(layer "B.Fab")
			(effects
				(font
					(size 1.27 1.27)
				)
				(justify mirror)
			)
		)
		(duplicate_pad_numbers_are_jumpers no)
		(fp_poly
			(pts
				(xy -0.3048 -0.1016) (xy -0.3048 0.9906) (xy 0.3048 0.9906) (xy 0.3048 -0.1016)
			)
			(stroke
				(width 0)
				(type default)
			)
			(fill no)
			(layer "B.CrtYd")
		)
		(fp_line
			(start 0.3048 -0.1016)
			(end 0.3048 0.9906)
			(stroke
				(width 0.1)
				(type default)
			)
			(layer "B.Fab")
		)
		(fp_line
			(start -0.3048 -0.1016)
			(end 0.3048 -0.1016)
			(stroke
				(width 0.1)
				(type default)
			)
			(layer "B.Fab")
		)
		(fp_line
			(start 0.3048 0.9906)
			(end -0.3048 0.9906)
			(stroke
				(width 0.1)
				(type default)
			)
			(layer "B.Fab")
		)
		(fp_line
			(start -0.3048 0.9906)
			(end -0.3048 -0.1016)
			(stroke
				(width 0.1)
				(type default)
			)
			(layer "B.Fab")
		)
		(pad "1" smd rect
			(at 0 0 270)
			(size 0.508 0.508)
			(layers "B.Cu" "B.Mask" "B.Paste")
			(net "P3V3_STBY")
		)
		(pad "2" smd rect
			(at 0 0.889 270)
			(size 0.508 0.508)
			(layers "B.Cu" "B.Mask" "B.Paste")
			(net "GND")
		)
		(zone
			(layer "B.Cu")
			(hatch none 0.5)
			(connect_pads
				(clearance 0)
			)
			(min_thickness 0.25)
			(keepout
				(tracks allowed)
				(vias not_allowed)
				(pads allowed)
				(copperpour not_allowed)
				(footprints allowed)
			)
			(placement
				(enabled no)
				(sheetname "")
			)
			(fill
				(thermal_gap 0.5)
				(thermal_bridge_width 0.5)
				(island_removal_mode 0)
			)
			(polygon
				(pts
					(xy 373.271288 -36.350448) (xy 373.271288 -35.842448) (xy 373.652288 -35.842448) (xy 373.652288 -36.350448)
				)
			)
		)
		(zone
			(layer "B.Cu")
			(hatch none 0.5)
			(connect_pads
				(clearance 0)
			)
			(min_thickness 0.25)
			(keepout
				(tracks not_allowed)
				(vias allowed)
				(pads allowed)
				(copperpour not_allowed)
				(footprints allowed)
			)
			(placement
				(enabled no)
				(sheetname "")
			)
			(fill
				(thermal_gap 0.5)
				(thermal_bridge_width 0.5)
				(island_removal_mode 0)
			)
			(polygon
				(pts
					(xy 373.652288 -36.350448) (xy 373.652288 -35.842448) (xy 373.271288 -35.842448) (xy 373.271288 -36.350448)
				)
			)
		)
	)
	(footprint ""
		(layer "B.Cu")
		(at 349.463614 -123.576842 -90)
		(property "Reference" "C3M13"
			(at 0 0 90)
			(layer "B.SilkS")
			(hide yes)
			(effects
				(font
					(size 1.27 1.27)
				)
				(justify mirror)
			)
		)
		(property "Value" ""
			(at 0 0 90)
			(layer "B.Fab")
			(effects
				(font
					(size 1.27 1.27)
				)
				(justify mirror)
			)
		)
		(duplicate_pad_numbers_are_jumpers no)
		(fp_poly
			(pts
				(xy -0.3048 -0.1016) (xy -0.3048 0.9906) (xy 0.3048 0.9906) (xy 0.3048 -0.1016)
			)
			(stroke
				(width 0)
				(type default)
			)
			(fill no)
			(layer "B.CrtYd")
		)
		(fp_line
			(start -0.3048 0.9906)
			(end -0.3048 -0.1016)
			(stroke
				(width 0.1)
				(type default)
			)
			(layer "B.Fab")
		)
		(fp_line
			(start 0.3048 0.9906)
			(end -0.3048 0.9906)
			(stroke
				(width 0.1)
				(type default)
			)
			(layer "B.Fab")
		)
		(fp_line
			(start -0.3048 -0.1016)
			(end 0.3048 -0.1016)
			(stroke
				(width 0.1)
				(type default)
			)
			(layer "B.Fab")
		)
		(fp_line
			(start 0.3048 -0.1016)
			(end 0.3048 0.9906)
			(stroke
				(width 0.1)
				(type default)
			)
			(layer "B.Fab")
		)
		(pad "1" smd rect
			(at 0 0 90)
			(size 0.508 0.508)
			(layers "B.Cu" "B.Mask" "B.Paste")
			(net "P3E_CPU0_PE1_PCH_R_RXP<13>")
		)
		(pad "2" smd rect
			(at 0 0.889 90)
			(size 0.508 0.508)
			(layers "B.Cu" "B.Mask" "B.Paste")
			(net "P3E_CPU0_PE1_PCH_RXP<13>")
		)
		(zone
			(layer "B.Cu")
			(hatch none 0.5)
			(connect_pads
				(clearance 0)
			)
			(min_thickness 0.25)
			(keepout
				(tracks not_allowed)
				(vias allowed)
				(pads allowed)
				(copperpour not_allowed)
				(footprints allowed)
			)
			(placement
				(enabled no)
				(sheetname "")
			)
			(fill
				(thermal_gap 0.5)
				(thermal_bridge_width 0.5)
				(island_removal_mode 0)
			)
			(polygon
				(pts
					(xy 348.828614 -123.322842) (xy 348.828614 -123.830842) (xy 349.209614 -123.830842) (xy 349.209614 -123.322842)
				)
			)
		)
		(zone
			(layer "B.Cu")
			(hatch none 0.5)
			(connect_pads
				(clearance 0)
			)
			(min_thickness 0.25)
			(keepout
				(tracks allowed)
				(vias not_allowed)
				(pads allowed)
				(copperpour not_allowed)
				(footprints allowed)
			)
			(placement
				(enabled no)
				(sheetname "")
			)
			(fill
				(thermal_gap 0.5)
				(thermal_bridge_width 0.5)
				(island_removal_mode 0)
			)
			(polygon
				(pts
					(xy 349.209614 -123.322842) (xy 349.209614 -123.830842) (xy 348.828614 -123.830842) (xy 348.828614 -123.322842)
				)
			)
		)
	)
	(footprint ""
		(layer "B.Cu")
		(at 348.5134 -152.038304 -90)
		(property "Reference" "C3L15"
			(at 0 0 90)
			(layer "B.SilkS")
			(hide yes)
			(effects
				(font
					(size 1.27 1.27)
				)
				(justify mirror)
			)
		)
		(property "Value" ""
			(at 0 0 90)
			(layer "B.Fab")
			(effects
				(font
					(size 1.27 1.27)
				)
				(justify mirror)
			)
		)
		(duplicate_pad_numbers_are_jumpers no)
		(fp_poly
			(pts
				(xy 0.7239 -0.2159) (xy -0.7239 -0.2159) (xy -0.7239 1.9939) (xy 0.7239 1.9939)
			)
			(stroke
				(width 0)
				(type default)
			)
			(fill no)
			(layer "B.CrtYd")
		)
		(fp_line
			(start -0.7239 1.9939)
			(end -0.7239 -0.2159)
			(stroke
				(width 0.1)
				(type default)
			)
			(layer "B.Fab")
		)
		(fp_line
			(start 0.7239 1.9939)
			(end -0.7239 1.9939)
			(stroke
				(width 0.1)
				(type default)
			)
			(layer "B.Fab")
		)
		(fp_line
			(start -0.7239 -0.2159)
			(end 0.7239 -0.2159)
			(stroke
				(width 0.1)
				(type default)
			)
			(layer "B.Fab")
		)
		(fp_line
			(start 0.7239 -0.2159)
			(end 0.7239 1.9939)
			(stroke
				(width 0.1)
				(type default)
			)
			(layer "B.Fab")
		)
		(pad "1" smd rect
			(at 0 0 90)
			(size 1.27 1.016)
			(layers "B.Cu" "B.Mask" "B.Paste")
			(net "VR_FET_SW_P12V_STBY_PVDDQ_DEF")
		)
		(pad "2" smd rect
			(at 0 1.778 90)
			(size 1.27 1.016)
			(layers "B.Cu" "B.Mask" "B.Paste")
			(net "GND")
		)
		(zone
			(layer "B.Cu")
			(hatch none 0.5)
			(connect_pads
				(clearance 0)
			)
			(min_thickness 0.25)
			(keepout
				(tracks not_allowed)
				(vias allowed)
				(pads allowed)
				(copperpour not_allowed)
				(footprints allowed)
			)
			(placement
				(enabled no)
				(sheetname "")
			)
			(fill
				(thermal_gap 0.5)
				(thermal_bridge_width 0.5)
				(island_removal_mode 0)
			)
			(polygon
				(pts
					(xy 348.0054 -151.403304) (xy 348.0054 -152.673304) (xy 347.2434 -152.673304) (xy 347.2434 -151.403304)
				)
			)
		)
	)
	(footprint ""
		(layer "B.Cu")
		(at 430.2125 -12.446 -90)
		(property "Reference" "R1U59"
			(at 0 0 90)
			(layer "B.SilkS")
			(hide yes)
			(effects
				(font
					(size 1.27 1.27)
				)
				(justify mirror)
			)
		)
		(property "Value" ""
			(at 0 0 90)
			(layer "B.Fab")
			(effects
				(font
					(size 1.27 1.27)
				)
				(justify mirror)
			)
		)
		(duplicate_pad_numbers_are_jumpers no)
		(fp_poly
			(pts
				(xy 0.2794 -0.1016) (xy -0.2794 -0.1016) (xy -0.2794 0.9906) (xy 0.2794 0.9906)
			)
			(stroke
				(width 0)
				(type default)
			)
			(fill no)
			(layer "B.CrtYd")
		)
		(fp_line
			(start -0.2794 0.9906)
			(end -0.2794 -0.1016)
			(stroke
				(width 0.1)
				(type default)
			)
			(layer "B.Fab")
		)
		(fp_line
			(start 0.2794 0.9906)
			(end -0.2794 0.9906)
			(stroke
				(width 0.1)
				(type default)
			)
			(layer "B.Fab")
		)
		(fp_line
			(start -0.2794 -0.1016)
			(end 0.2794 -0.1016)
			(stroke
				(width 0.1)
				(type default)
			)
			(layer "B.Fab")
		)
		(fp_line
			(start 0.2794 -0.1016)
			(end 0.2794 0.9906)
			(stroke
				(width 0.1)
				(type default)
			)
			(layer "B.Fab")
		)
		(pad "1" smd rect
			(at 0 0 90)
			(size 0.508 0.508)
			(layers "B.Cu" "B.Mask" "B.Paste")
			(net "H_CPU0_ABC_MEMHOT_LVT3_R_N")
		)
		(pad "2" smd rect
			(at 0 0.889 90)
			(size 0.508 0.508)
			(layers "B.Cu" "B.Mask" "B.Paste")
			(net "H_CPU0_MEMABC_MEMHOT_LVT3_K_N")
		)
		(zone
			(layer "B.Cu")
			(hatch none 0.5)
			(connect_pads
				(clearance 0)
			)
			(min_thickness 0.25)
			(keepout
				(tracks not_allowed)
				(vias allowed)
				(pads allowed)
				(copperpour not_allowed)
				(footprints allowed)
			)
			(placement
				(enabled no)
				(sheetname "")
			)
			(fill
				(thermal_gap 0.5)
				(thermal_bridge_width 0.5)
				(island_removal_mode 0)
			)
			(polygon
				(pts
					(xy 429.5775 -12.192) (xy 429.5775 -12.7) (xy 429.9585 -12.7) (xy 429.9585 -12.192)
				)
			)
		)
		(zone
			(layer "B.Cu")
			(hatch none 0.5)
			(connect_pads
				(clearance 0)
			)
			(min_thickness 0.25)
			(keepout
				(tracks allowed)
				(vias not_allowed)
				(pads allowed)
				(copperpour not_allowed)
				(footprints allowed)
			)
			(placement
				(enabled no)
				(sheetname "")
			)
			(fill
				(thermal_gap 0.5)
				(thermal_bridge_width 0.5)
				(island_removal_mode 0)
			)
			(polygon
				(pts
					(xy 429.9585 -12.192) (xy 429.9585 -12.7) (xy 429.5775 -12.7) (xy 429.5775 -12.192)
				)
			)
		)
	)
	(footprint ""
		(layer "B.Cu")
		(at 383.019808 -155.432506)
		(property "Reference" "R3L4"
			(at 0 0 0)
			(layer "B.SilkS")
			(hide yes)
			(effects
				(font
					(size 1.27 1.27)
				)
				(justify mirror)
			)
		)
		(property "Value" ""
			(at 0 0 0)
			(layer "B.Fab")
			(effects
				(font
					(size 1.27 1.27)
				)
				(justify mirror)
			)
		)
		(duplicate_pad_numbers_are_jumpers no)
		(fp_poly
			(pts
				(xy 0.2794 -0.1016) (xy -0.2794 -0.1016) (xy -0.2794 0.9906) (xy 0.2794 0.9906)
			)
			(stroke
				(width 0)
				(type default)
			)
			(fill no)
			(layer "B.CrtYd")
		)
		(fp_line
			(start -0.2794 -0.1016)
			(end 0.2794 -0.1016)
			(stroke
				(width 0.1)
				(type default)
			)
			(layer "B.Fab")
		)
		(fp_line
			(start -0.2794 0.9906)
			(end -0.2794 -0.1016)
			(stroke
				(width 0.1)
				(type default)
			)
			(layer "B.Fab")
		)
		(fp_line
			(start 0.2794 -0.1016)
			(end 0.2794 0.9906)
			(stroke
				(width 0.1)
				(type default)
			)
			(layer "B.Fab")
		)
		(fp_line
			(start 0.2794 0.9906)
			(end -0.2794 0.9906)
			(stroke
				(width 0.1)
				(type default)
			)
			(layer "B.Fab")
		)
		(pad "1" smd rect
			(at 0 0 180)
			(size 0.508 0.508)
			(layers "B.Cu" "B.Mask" "B.Paste")
			(net "VR_P1V05_PCH_STBY_PH1_VCIN")
		)
		(pad "2" smd rect
			(at 0 0.889 180)
			(size 0.508 0.508)
			(layers "B.Cu" "B.Mask" "B.Paste")
			(net "P5V_STBY")
		)
		(zone
			(layer "B.Cu")
			(hatch none 0.5)
			(connect_pads
				(clearance 0)
			)
			(min_thickness 0.25)
			(keepout
				(tracks allowed)
				(vias not_allowed)
				(pads allowed)
				(copperpour not_allowed)
				(footprints allowed)
			)
			(placement
				(enabled no)
				(sheetname "")
			)
			(fill
				(thermal_gap 0.5)
				(thermal_bridge_width 0.5)
				(island_removal_mode 0)
			)
			(polygon
				(pts
					(xy 383.273808 -155.178506) (xy 382.765808 -155.178506) (xy 382.765808 -154.797506) (xy 383.273808 -154.797506)
				)
			)
		)
		(zone
			(layer "B.Cu")
			(hatch none 0.5)
			(connect_pads
				(clearance 0)
			)
			(min_thickness 0.25)
			(keepout
				(tracks not_allowed)
				(vias allowed)
				(pads allowed)
				(copperpour not_allowed)
				(footprints allowed)
			)
			(placement
				(enabled no)
				(sheetname "")
			)
			(fill
				(thermal_gap 0.5)
				(thermal_bridge_width 0.5)
				(island_removal_mode 0)
			)
			(polygon
				(pts
					(xy 383.273808 -154.797506) (xy 382.765808 -154.797506) (xy 382.765808 -155.178506) (xy 383.273808 -155.178506)
				)
			)
		)
	)
	(footprint ""
		(layer "B.Cu")
		(at 382.7272 -114.554 180)
		(property "Reference" "C3M39"
			(at 0 0 0)
			(layer "B.SilkS")
			(hide yes)
			(effects
				(font
					(size 1.27 1.27)
				)
				(justify mirror)
			)
		)
		(property "Value" ""
			(at 0 0 0)
			(layer "B.Fab")
			(effects
				(font
					(size 1.27 1.27)
				)
				(justify mirror)
			)
		)
		(duplicate_pad_numbers_are_jumpers no)
		(fp_poly
			(pts
				(xy -0.3048 -0.1016) (xy -0.3048 0.9906) (xy 0.3048 0.9906) (xy 0.3048 -0.1016)
			)
			(stroke
				(width 0)
				(type default)
			)
			(fill no)
			(layer "B.CrtYd")
		)
		(fp_line
			(start 0.3048 0.9906)
			(end -0.3048 0.9906)
			(stroke
				(width 0.1)
				(type default)
			)
			(layer "B.Fab")
		)
		(fp_line
			(start 0.3048 -0.1016)
			(end 0.3048 0.9906)
			(stroke
				(width 0.1)
				(type default)
			)
			(layer "B.Fab")
		)
		(fp_line
			(start -0.3048 0.9906)
			(end -0.3048 -0.1016)
			(stroke
				(width 0.1)
				(type default)
			)
			(layer "B.Fab")
		)
		(fp_line
			(start -0.3048 -0.1016)
			(end 0.3048 -0.1016)
			(stroke
				(width 0.1)
				(type default)
			)
			(layer "B.Fab")
		)
		(pad "1" smd rect
			(at 0 0)
			(size 0.508 0.508)
			(layers "B.Cu" "B.Mask" "B.Paste")
			(net "P1V05_PCH_STBY")
		)
		(pad "2" smd rect
			(at 0 0.889)
			(size 0.508 0.508)
			(layers "B.Cu" "B.Mask" "B.Paste")
			(net "GND")
		)
		(zone
			(layer "B.Cu")
			(hatch none 0.5)
			(connect_pads
				(clearance 0)
			)
			(min_thickness 0.25)
			(keepout
				(tracks not_allowed)
				(vias allowed)
				(pads allowed)
				(copperpour not_allowed)
				(footprints allowed)
			)
			(placement
				(enabled no)
				(sheetname "")
			)
			(fill
				(thermal_gap 0.5)
				(thermal_bridge_width 0.5)
				(island_removal_mode 0)
			)
			(polygon
				(pts
					(xy 382.4732 -115.189) (xy 382.9812 -115.189) (xy 382.9812 -114.808) (xy 382.4732 -114.808)
				)
			)
		)
		(zone
			(layer "B.Cu")
			(hatch none 0.5)
			(connect_pads
				(clearance 0)
			)
			(min_thickness 0.25)
			(keepout
				(tracks allowed)
				(vias not_allowed)
				(pads allowed)
				(copperpour not_allowed)
				(footprints allowed)
			)
			(placement
				(enabled no)
				(sheetname "")
			)
			(fill
				(thermal_gap 0.5)
				(thermal_bridge_width 0.5)
				(island_removal_mode 0)
			)
			(polygon
				(pts
					(xy 382.4732 -114.808) (xy 382.9812 -114.808) (xy 382.9812 -115.189) (xy 382.4732 -115.189)
				)
			)
		)
	)
	(footprint ""
		(layer "B.Cu")
		(at 480.037902 -54.339998)
		(property "Reference" "C8E5"
			(at 0 0 0)
			(layer "B.SilkS")
			(hide yes)
			(effects
				(font
					(size 1.27 1.27)
				)
				(justify mirror)
			)
		)
		(property "Value" ""
			(at 0 0 0)
			(layer "B.Fab")
			(effects
				(font
					(size 1.27 1.27)
				)
				(justify mirror)
			)
		)
		(duplicate_pad_numbers_are_jumpers no)
		(fp_poly
			(pts
				(xy -0.3048 -0.1016) (xy -0.3048 0.9906) (xy 0.3048 0.9906) (xy 0.3048 -0.1016)
			)
			(stroke
				(width 0)
				(type default)
			)
			(fill no)
			(layer "B.CrtYd")
		)
		(fp_line
			(start -0.3048 -0.1016)
			(end 0.3048 -0.1016)
			(stroke
				(width 0.1)
				(type default)
			)
			(layer "B.Fab")
		)
		(fp_line
			(start -0.3048 0.9906)
			(end -0.3048 -0.1016)
			(stroke
				(width 0.1)
				(type default)
			)
			(layer "B.Fab")
		)
		(fp_line
			(start 0.3048 -0.1016)
			(end 0.3048 0.9906)
			(stroke
				(width 0.1)
				(type default)
			)
			(layer "B.Fab")
		)
		(fp_line
			(start 0.3048 0.9906)
			(end -0.3048 0.9906)
			(stroke
				(width 0.1)
				(type default)
			)
			(layer "B.Fab")
		)
		(pad "1" smd rect
			(at 0 0 180)
			(size 0.508 0.508)
			(layers "B.Cu" "B.Mask" "B.Paste")
			(net "P3V3_STBY")
		)
		(pad "2" smd rect
			(at 0 0.889 180)
			(size 0.508 0.508)
			(layers "B.Cu" "B.Mask" "B.Paste")
			(net "GND")
		)
		(zone
			(layer "B.Cu")
			(hatch none 0.5)
			(connect_pads
				(clearance 0)
			)
			(min_thickness 0.25)
			(keepout
				(tracks allowed)
				(vias not_allowed)
				(pads allowed)
				(copperpour not_allowed)
				(footprints allowed)
			)
			(placement
				(enabled no)
				(sheetname "")
			)
			(fill
				(thermal_gap 0.5)
				(thermal_bridge_width 0.5)
				(island_removal_mode 0)
			)
			(polygon
				(pts
					(xy 480.291902 -54.085998) (xy 479.783902 -54.085998) (xy 479.783902 -53.704998) (xy 480.291902 -53.704998)
				)
			)
		)
		(zone
			(layer "B.Cu")
			(hatch none 0.5)
			(connect_pads
				(clearance 0)
			)
			(min_thickness 0.25)
			(keepout
				(tracks not_allowed)
				(vias allowed)
				(pads allowed)
				(copperpour not_allowed)
				(footprints allowed)
			)
			(placement
				(enabled no)
				(sheetname "")
			)
			(fill
				(thermal_gap 0.5)
				(thermal_bridge_width 0.5)
				(island_removal_mode 0)
			)
			(polygon
				(pts
					(xy 480.291902 -53.704998) (xy 479.783902 -53.704998) (xy 479.783902 -54.085998) (xy 480.291902 -54.085998)
				)
			)
		)
	)
)
